# BASEBOARD_FAB2 (Tioga Pass) — schematic netlist excerpt (pin names and nets, part order shuffled) for the footprints in the layout excerpt that follows; sources: Cadence DE-HDL packaged netlist, KiCad conversion of Wiwynn_Tioga_Pass_MB.brd

J6U2  SCONN288_H44441003  SCONN  pkg PIP  page 48
  \12v\(1)  = P12V_NVDIMM_ABC
  VSS(93)  = GND
  DQ(4)  = M_C_DQ<4>
  VSS(92)  = GND
  DQ(0)  = M_C_DQ<0>
  VSS(91)  = GND
  DQS9P  = M_C_DQS_DP<9>
  DQS9N  = M_C_DQS_DN<9>
  VSS(90)  = GND
  DQ(6)  = M_C_DQ<6>
  VSS(89)  = GND
  DQ(2)  = M_C_DQ<2>
  VSS(88)  = GND
  DQ(12)  = M_C_DQ<12>
  VSS(87)  = GND
  DQ(8)  = M_C_DQ<8>
  VSS(86)  = GND
  DQS10P  = M_C_DQS_DP<10>
  DQS10N  = M_C_DQS_DN<10>
  VSS(85)  = GND
  DQ(14)  = M_C_DQ<14>
  VSS(84)  = GND
  DQ(10)  = M_C_DQ<10>
  VSS(83)  = GND
  DQ(20)  = M_C_DQ<20>
  VSS(82)  = GND
  DQ(16)  = M_C_DQ<16>
  VSS(81)  = GND
  DQS11P  = M_C_DQS_DP<11>
  DQS11N  = M_C_DQS_DN<11>
  VSS(80)  = GND
  DQ(22)  = M_C_DQ<22>
  VSS(79)  = GND
  DQ(18)  = M_C_DQ<18>
  VSS(78)  = GND
  DQ(28)  = M_C_DQ<28>
  VSS(77)  = GND
  DQ(24)  = M_C_DQ<24>
  VSS(76)  = GND
  DQS12P  = M_C_DQS_DP<12>
  DQS12N  = M_C_DQS_DN<12>
  VSS(75)  = GND
  DQ(30)  = M_C_DQ<30>
  VSS(74)  = GND
  DQ(26)  = M_C_DQ<26>
  VSS(73)  = GND
  CB(4)  = M_C_ECC<4>
  VSS(72)  = GND
  CB(0)  = M_C_ECC<0>
  VSS(71)  = GND
  DQS17P  = M_C_DQS_DP<17>
  DQS17N  = M_C_DQS_DN<17>
  VSS(70)  = GND
  CB(6)  = M_C_ECC<6>
  VSS(69)  = GND
  CB(2)  = M_C_ECC<2>
  VSS(68)  = GND
  RESET_N  = M_ABC_RST_N
  VDD(25)  = PVDDQ_ABC
  CKE(0)  = M_C_CKE<2>
  VDD(24)  = PVDDQ_ABC
  ACT_N  = M_C_ACT_N
  BG(0)  = M_C_BG<0>
  VDD(23)  = PVDDQ_ABC
  A12  = M_C_MA<12>
  A9  = M_C_MA<9>
  VDD(22)  = PVDDQ_ABC
  A8  = M_C_MA<8>
  A6  = M_C_MA<6>
  VDD(21)  = PVDDQ_ABC
  A3  = M_C_MA<3>
  A1  = M_C_MA<1>
  VDD(20)  = PVDDQ_ABC
  CK0P  = M_C_CLK_DP<2>
  CK0N  = M_C_CLK_DN<2>
  VDD(19)  = PVDDQ_ABC
  VTT(1)  = PVTT_ABC
  EVENT_N  = FM_DIMM_EVENT_COD_N
  A0  = M_C_MA<0>
  VDD(18)  = PVDDQ_ABC
  BA(0)  = M_C_BA<0>
  A16_RAS_N  = M_C_MA<16>
  VDD(17)  = PVDDQ_ABC
  S0_N  = M_C_CS_N<4>
  VDD(16)  = PVDDQ_ABC
  A15_CAS_N  = M_C_MA<15>
  ODT(0)  = M_C_ODT<2>
  VDD(15)  = PVDDQ_ABC
  S1_N  = M_C_CS_N<5>
  VDD(14)  = PVDDQ_ABC
  ODT(1)  = M_C_ODT<3>
  VDD(13)  = PVDDQ_ABC
  S2_N_C(0)  = M_C_CS_N<6>
  VSS(67)  = GND
  DQ(36)  = M_C_DQ<36>
  VSS(66)  = GND
  DQ(32)  = M_C_DQ<32>
  VSS(65)  = GND
  DQS13P  = M_C_DQS_DP<13>
  DQS13N  = M_C_DQS_DN<13>
  VSS(64)  = GND
  DQ(38)  = M_C_DQ<38>
  VSS(63)  = GND
  DQ(34)  = M_C_DQ<34>
  VSS(62)  = GND
  DQ(44)  = M_C_DQ<44>
  VSS(61)  = GND
  DQ(40)  = M_C_DQ<40>
  VSS(60)  = GND
  DQS14P  = M_C_DQS_DP<14>
  DQS14N  = M_C_DQS_DN<14>
  VSS(59)  = GND
  DQ(46)  = M_C_DQ<46>
  VSS(58)  = GND
  DQ(42)  = M_C_DQ<42>
  VSS(57)  = GND
  DQ(52)  = M_C_DQ<52>
  VSS(56)  = GND
  DQ(48)  = M_C_DQ<48>
  VSS(55)  = GND
  DQS15P  = M_C_DQS_DP<15>
  DQS15N  = M_C_DQS_DN<15>
  VSS(54)  = GND
  DQ(54)  = M_C_DQ<54>
  VSS(53)  = GND
  DQ(50)  = M_C_DQ<50>
  VSS(52)  = GND
  DQ(60)  = M_C_DQ<60>
  VSS(51)  = GND
  DQ(56)  = M_C_DQ<56>
  VSS(50)  = GND
  DQS16P  = M_C_DQS_DP<16>
  DQS16N  = M_C_DQS_DN<16>
  VSS(49)  = GND
  DQ(62)  = M_C_DQ<62>
  VSS(48)  = GND
  DQ(58)  = M_C_DQ<58>
  VSS(47)  = GND
  SA(0)  = PVPP_ABC
  SA(1)  = GND
  SCL  = SMB_DDR_ABC_VPP_SCL
  VPP(4)  = PVPP_ABC
  VPP(3)  = PVPP_ABC
  RFU(2)  = TP_CH_C_DIMM_C1_RFU_2
  \12v\(0)  = P12V_NVDIMM_ABC
  VREFCA  = M_C_VREF
  VSS(46)  = GND
  DQ(5)  = M_C_DQ<5>
  VSS(45)  = GND
  DQ(1)  = M_C_DQ<1>
  VSS(44)  = GND
  DQS0N  = M_C_DQS_DN<0>
  DQS0P  = M_C_DQS_DP<0>
  VSS(43)  = GND
  DQ(7)  = M_C_DQ<7>
  VSS(42)  = GND
  DQ(3)  = M_C_DQ<3>
  VSS(41)  = GND
  DQ(13)  = M_C_DQ<13>
  VSS(40)  = GND
  DQ(9)  = M_C_DQ<9>
  VSS(39)  = GND
  DQS1N  = M_C_DQS_DN<1>
  DQS1P  = M_C_DQS_DP<1>
  VSS(38)  = GND
  DQ(15)  = M_C_DQ<15>
  VSS(37)  = GND
  DQ(11)  = M_C_DQ<11>
  VSS(36)  = GND
  DQ(21)  = M_C_DQ<21>
  VSS(35)  = GND
  DQ(17)  = M_C_DQ<17>
  VSS(34)  = GND
  DQS2N  = M_C_DQS_DN<2>
  DQS2P  = M_C_DQS_DP<2>
  VSS(33)  = GND
  DQ(23)  = M_C_DQ<23>
  VSS(32)  = GND
  DQ(19)  = M_C_DQ<19>
  VSS(31)  = GND
  DQ(29)  = M_C_DQ<29>
  VSS(30)  = GND
  DQ(25)  = M_C_DQ<25>
  VSS(29)  = GND
  DQS3N  = M_C_DQS_DN<3>
  DQS3P  = M_C_DQS_DP<3>
  VSS(28)  = GND
  DQ(31)  = M_C_DQ<31>
  VSS(27)  = GND
  DQ(27)  = M_C_DQ<27>
  VSS(26)  = GND
  CB(5)  = M_C_ECC<5>
  VSS(25)  = GND
  CB(1)  = M_C_ECC<1>
  VSS(24)  = GND
  DQS8N  = M_C_DQS_DN<8>
  DQS8P  = M_C_DQS_DP<8>
  VSS(23)  = GND
  CB(7)  = M_C_ECC<7>
  VSS(22)  = GND
  CB(3)  = M_C_ECC<3>
  VSS(21)  = GND
  CKE(1)  = M_C_CKE<3>
  VDD(12)  = PVDDQ_ABC
  RFU(0)  = TP_CH_C_DIMM_C1_RFU_0
  VDD(11)  = PVDDQ_ABC
  BG(1)  = M_C_BG<1>
  ALERT_N  = M_C_ALERT_N
  VDD(10)  = PVDDQ_ABC
  A11  = M_C_MA<11>
  A7  = M_C_MA<7>
  VDD(9)  = PVDDQ_ABC
  A5  = M_C_MA<5>
  A4  = M_C_MA<4>
  VDD(8)  = PVDDQ_ABC
  A2  = M_C_MA<2>
  VDD(7)  = PVDDQ_ABC
  CK1P  = M_C_CLK_DP<3>
  CK1N  = M_C_CLK_DN<3>
  VDD(6)  = PVDDQ_ABC
  VTT(0)  = PVTT_ABC
  PAR  = M_C_PAR
  VDD(5)  = PVDDQ_ABC
  BA(1)  = M_C_BA<1>
  A10  = M_C_MA<10>
  VDD(4)  = PVDDQ_ABC
  RFU(1)  = TP_CH_C_DIMM_C1_RFU_1
  A14_WE_N  = M_C_MA<14>
  VDD(3)  = PVDDQ_ABC
  SAVE_N_NC  = FM_ADR_COMPLETE_ABC_N
  VDD(2)  = PVDDQ_ABC
  A13  = M_C_MA<13>
  VDD(1)  = PVDDQ_ABC
  A17  = M_C_MA<17>
  C(2)  = M_C_C<2>
  VDD(0)  = PVDDQ_ABC
  S3_N_C(1)  = M_C_CS_N<7>
  SA(2)  = PVPP_ABC
  VSS(20)  = GND
  DQ(37)  = M_C_DQ<37>
  VSS(19)  = GND
  DQ(33)  = M_C_DQ<33>
  VSS(18)  = GND
  DQS4N  = M_C_DQS_DN<4>
  DQS4P  = M_C_DQS_DP<4>
  VSS(17)  = GND
  DQ(39)  = M_C_DQ<39>
  VSS(16)  = GND
  DQ(35)  = M_C_DQ<35>
  VSS(15)  = GND
  DQ(45)  = M_C_DQ<45>
  VSS(14)  = GND
  DQ(41)  = M_C_DQ<41>
  VSS(13)  = GND
  DQS5N  = M_C_DQS_DN<5>
  DQS5P  = M_C_DQS_DP<5>
  VSS(12)  = GND
  DQ(47)  = M_C_DQ<47>
  VSS(11)  = GND
  DQ(43)  = M_C_DQ<43>
  VSS(10)  = GND
  DQ(53)  = M_C_DQ<53>
  VSS(9)  = GND
  DQ(49)  = M_C_DQ<49>
  VSS(8)  = GND
  DQS6N  = M_C_DQS_DN<6>
  DQS6P  = M_C_DQS_DP<6>
  VSS(7)  = GND
  DQ(55)  = M_C_DQ<55>
  VSS(6)  = GND
  DQ(51)  = M_C_DQ<51>
  VSS(5)  = GND
  DQ(61)  = M_C_DQ<61>
  VSS(4)  = GND
  DQ(57)  = M_C_DQ<57>
  VSS(3)  = GND
  DQS7N  = M_C_DQS_DN<7>
  DQS7P  = M_C_DQS_DP<7>
  VSS(2)  = GND
  DQ(63)  = M_C_DQ<63>
  VSS(1)  = GND
  DQ(59)  = M_C_DQ<59>
  VSS(0)  = GND
  VDDSPD  = PVPP_ABC
  SDA  = SMB_DDR_ABC_VPP_SDA
  VPP(1)  = PVPP_ABC
  VPP(0)  = PVPP_ABC
  VPP(2)  = PVPP_ABC

(kicad_pcb
	(version 20260206)
	(generator "pcbnew")
	(generator_version "10.0")
	(general
		(thickness 1.6)
		(legacy_teardrops no)
	)
	(paper "A4")
	(title_block
		(title "Wiwynn_Tioga_Pass_MB.brd")
		(comment 1 "Tioga Pass / footprint 2838 of 4770 (J6U2), pads 51-100 of 291")
	)
	(layers
		(0 "F.Cu" signal "TOP")
		(4 "In1.Cu" signal "L2GND")
		(6 "In2.Cu" signal "L3")
		(8 "In3.Cu" signal "L4GND")
		(10 "In4.Cu" signal "L5")
		(12 "In5.Cu" signal "L6GND")
		(14 "In6.Cu" signal "L7VCC")
		(16 "In7.Cu" signal "L8VCC")
		(18 "In8.Cu" signal "L9GND")
		(20 "In9.Cu" signal "L10")
		(22 "In10.Cu" signal "L11GND")
		(24 "In11.Cu" signal "L12")
		(26 "In12.Cu" signal "L13GND")
		(2 "B.Cu" signal "BOTTOM")
		(9 "F.Adhes" user "F.Adhesive")
		(11 "B.Adhes" user "B.Adhesive")
		(13 "F.Paste" user "Package Geometry/Pastemask Top")
		(15 "B.Paste" user "Package Geometry/Pastemask Bottom")
		(5 "F.SilkS" user "Ref Des/Silkscreen Top")
		(7 "B.SilkS" user "Ref Des/Silkscreen Bottom")
		(1 "F.Mask" user "Board Geometry/Soldermask Top")
		(3 "B.Mask" user "Board Geometry/Soldermask Bottom")
		(17 "Dwgs.User" user "User.Drawings")
		(19 "Cmts.User" user "User.Comments")
		(21 "Eco1.User" user "User.Eco1")
		(23 "Eco2.User" user "User.Eco2")
		(25 "Edge.Cuts" user "Board Geometry/Outline")
		(27 "Margin" user)
		(31 "F.CrtYd" user "Package Geometry/Place Bound Top")
		(29 "B.CrtYd" user "Package Geometry/Place Bound Bottom")
		(35 "F.Fab" user "Ref Des/Assembly Top")
		(33 "B.Fab" user "Ref Des/Assembly Bottom")
	)
	(footprint ""
		(layer "B.Cu")
		(at 194.700398 -5.621782 90)
		(property "Reference" "J6U2"
			(at 2.225548 39.48811 0)
			(unlocked yes)
			(layer "B.SilkS")
			(effects
				(font
					(size 0.7874 0.5842)
					(thickness 0.1524)
				)
				(justify left mirror)
			)
		)
		(property "Value" ""
			(at 0 0 90)
			(layer "B.Fab")
			(effects
				(font
					(size 1.27 1.27)
				)
				(justify mirror)
			)
		)
		(duplicate_pad_numbers_are_jumpers no)
		(pad "48" smd rect
			(at 0 39.949882 270)
			(size 1.8034 0.508)
			(layers "B.Cu" "B.Mask" "B.Paste")
			(net "GND")
		)
		(pad "49" smd rect
			(at 0 40.80002 270)
			(size 1.8034 0.508)
			(layers "B.Cu" "B.Mask" "B.Paste")
			(net "M_C_ECC<0>")
		)
		(pad "50" smd rect
			(at 0 41.649904 270)
			(size 1.8034 0.508)
			(layers "B.Cu" "B.Mask" "B.Paste")
			(net "GND")
		)
		(pad "51" smd rect
			(at 0 42.500042 270)
			(size 1.8034 0.508)
			(layers "B.Cu" "B.Mask" "B.Paste")
			(net "M_C_DQS_DP<17>")
		)
		(pad "52" smd rect
			(at 0 43.349926 270)
			(size 1.8034 0.508)
			(layers "B.Cu" "B.Mask" "B.Paste")
			(net "M_C_DQS_DN<17>")
		)
		(pad "53" smd rect
			(at 0 44.200064 270)
			(size 1.8034 0.508)
			(layers "B.Cu" "B.Mask" "B.Paste")
			(net "GND")
		)
		(pad "54" smd rect
			(at 0 45.049948 270)
			(size 1.8034 0.508)
			(layers "B.Cu" "B.Mask" "B.Paste")
			(net "M_C_ECC<6>")
		)
		(pad "55" smd rect
			(at 0 45.900086 270)
			(size 1.8034 0.508)
			(layers "B.Cu" "B.Mask" "B.Paste")
			(net "GND")
		)
		(pad "56" smd rect
			(at 0 46.74997 270)
			(size 1.8034 0.508)
			(layers "B.Cu" "B.Mask" "B.Paste")
			(net "M_C_ECC<2>")
		)
		(pad "57" smd rect
			(at 0 47.600108 270)
			(size 1.8034 0.508)
			(layers "B.Cu" "B.Mask" "B.Paste")
			(net "GND")
		)
		(pad "58" smd rect
			(at 0 48.449992 270)
			(size 1.8034 0.508)
			(layers "B.Cu" "B.Mask" "B.Paste")
			(net "M_ABC_RST_N")
		)
		(pad "59" smd rect
			(at 0 49.299876 270)
			(size 1.8034 0.508)
			(layers "B.Cu" "B.Mask" "B.Paste")
			(net "PVDDQ_ABC")
		)
		(pad "60" smd rect
			(at 0 50.150014 270)
			(size 1.8034 0.508)
			(layers "B.Cu" "B.Mask" "B.Paste")
			(net "M_C_CKE<2>")
		)
		(pad "61" smd rect
			(at 0 50.999898 270)
			(size 1.8034 0.508)
			(layers "B.Cu" "B.Mask" "B.Paste")
			(net "PVDDQ_ABC")
		)
		(pad "62" smd rect
			(at 0 51.850036 270)
			(size 1.8034 0.508)
			(layers "B.Cu" "B.Mask" "B.Paste")
			(net "M_C_ACT_N")
		)
		(pad "63" smd rect
			(at 0 52.69992 270)
			(size 1.8034 0.508)
			(layers "B.Cu" "B.Mask" "B.Paste")
			(net "M_C_BG<0>")
		)
		(pad "64" smd rect
			(at 0 53.550058 270)
			(size 1.8034 0.508)
			(layers "B.Cu" "B.Mask" "B.Paste")
			(net "PVDDQ_ABC")
		)
		(pad "65" smd rect
			(at 0 54.399942 270)
			(size 1.8034 0.508)
			(layers "B.Cu" "B.Mask" "B.Paste")
			(net "M_C_MA<12>")
		)
		(pad "66" smd rect
			(at 0 55.25008 270)
			(size 1.8034 0.508)
			(layers "B.Cu" "B.Mask" "B.Paste")
			(net "M_C_MA<9>")
		)
		(pad "67" smd rect
			(at 0 56.099964 270)
			(size 1.8034 0.508)
			(layers "B.Cu" "B.Mask" "B.Paste")
			(net "PVDDQ_ABC")
		)
		(pad "68" smd rect
			(at 0 56.950102 270)
			(size 1.8034 0.508)
			(layers "B.Cu" "B.Mask" "B.Paste")
			(net "M_C_MA<8>")
		)
		(pad "69" smd rect
			(at 0 57.799986 270)
			(size 1.8034 0.508)
			(layers "B.Cu" "B.Mask" "B.Paste")
			(net "M_C_MA<6>")
		)
		(pad "70" smd rect
			(at 0 58.650124 270)
			(size 1.8034 0.508)
			(layers "B.Cu" "B.Mask" "B.Paste")
			(net "PVDDQ_ABC")
		)
		(pad "71" smd rect
			(at 0 59.500008 270)
			(size 1.8034 0.508)
			(layers "B.Cu" "B.Mask" "B.Paste")
			(net "M_C_MA<3>")
		)
		(pad "72" smd rect
			(at 0 60.349892 270)
			(size 1.8034 0.508)
			(layers "B.Cu" "B.Mask" "B.Paste")
			(net "M_C_MA<1>")
		)
		(pad "73" smd rect
			(at 0 61.20003 270)
			(size 1.8034 0.508)
			(layers "B.Cu" "B.Mask" "B.Paste")
			(net "PVDDQ_ABC")
		)
		(pad "74" smd rect
			(at 0 62.049914 270)
			(size 1.8034 0.508)
			(layers "B.Cu" "B.Mask" "B.Paste")
			(net "M_C_CLK_DP<2>")
		)
		(pad "75" smd rect
			(at 0 62.900052 270)
			(size 1.8034 0.508)
			(layers "B.Cu" "B.Mask" "B.Paste")
			(net "M_C_CLK_DN<2>")
		)
		(pad "76" smd rect
			(at 0 63.749936 270)
			(size 1.8034 0.508)
			(layers "B.Cu" "B.Mask" "B.Paste")
			(net "PVDDQ_ABC")
		)
		(pad "77" smd rect
			(at 0 64.600074 270)
			(size 1.8034 0.508)
			(layers "B.Cu" "B.Mask" "B.Paste")
			(net "PVTT_ABC")
		)
		(pad "78" smd rect
			(at 0 70.550024 270)
			(size 1.8034 0.508)
			(layers "B.Cu" "B.Mask" "B.Paste")
			(net "FM_DIMM_EVENT_COD_N")
		)
		(pad "79" smd rect
			(at 0 71.399908 270)
			(size 1.8034 0.508)
			(layers "B.Cu" "B.Mask" "B.Paste")
			(net "M_C_MA<0>")
		)
		(pad "80" smd rect
			(at 0 72.250046 270)
			(size 1.8034 0.508)
			(layers "B.Cu" "B.Mask" "B.Paste")
			(net "PVDDQ_ABC")
		)
		(pad "81" smd rect
			(at 0 73.09993 270)
			(size 1.8034 0.508)
			(layers "B.Cu" "B.Mask" "B.Paste")
			(net "M_C_BA<0>")
		)
		(pad "82" smd rect
			(at 0 73.950068 270)
			(size 1.8034 0.508)
			(layers "B.Cu" "B.Mask" "B.Paste")
			(net "M_C_MA<16>")
		)
		(pad "83" smd rect
			(at 0 74.799952 270)
			(size 1.8034 0.508)
			(layers "B.Cu" "B.Mask" "B.Paste")
			(net "PVDDQ_ABC")
		)
		(pad "84" smd rect
			(at 0 75.65009 270)
			(size 1.8034 0.508)
			(layers "B.Cu" "B.Mask" "B.Paste")
			(net "M_C_CS_N<4>")
		)
		(pad "85" smd rect
			(at 0 76.499974 270)
			(size 1.8034 0.508)
			(layers "B.Cu" "B.Mask" "B.Paste")
			(net "PVDDQ_ABC")
		)
		(pad "86" smd rect
			(at 0 77.350112 270)
			(size 1.8034 0.508)
			(layers "B.Cu" "B.Mask" "B.Paste")
			(net "M_C_MA<15>")
		)
		(pad "87" smd rect
			(at 0 78.199996 270)
			(size 1.8034 0.508)
			(layers "B.Cu" "B.Mask" "B.Paste")
			(net "M_C_ODT<2>")
		)
		(pad "88" smd rect
			(at 0 79.04988 270)
			(size 1.8034 0.508)
			(layers "B.Cu" "B.Mask" "B.Paste")
			(net "PVDDQ_ABC")
		)
		(pad "89" smd rect
			(at 0 79.900018 270)
			(size 1.8034 0.508)
			(layers "B.Cu" "B.Mask" "B.Paste")
			(net "M_C_CS_N<5>")
		)
		(pad "90" smd rect
			(at 0 80.749902 270)
			(size 1.8034 0.508)
			(layers "B.Cu" "B.Mask" "B.Paste")
			(net "PVDDQ_ABC")
		)
		(pad "91" smd rect
			(at 0 81.60004 270)
			(size 1.8034 0.508)
			(layers "B.Cu" "B.Mask" "B.Paste")
			(net "M_C_ODT<3>")
		)
		(pad "92" smd rect
			(at 0 82.449924 270)
			(size 1.8034 0.508)
			(layers "B.Cu" "B.Mask" "B.Paste")
			(net "PVDDQ_ABC")
		)
		(pad "93" smd rect
			(at 0 83.300062 270)
			(size 1.8034 0.508)
			(layers "B.Cu" "B.Mask" "B.Paste")
			(net "M_C_CS_N<6>")
		)
		(pad "94" smd rect
			(at 0 84.149946 270)
			(size 1.8034 0.508)
			(layers "B.Cu" "B.Mask" "B.Paste")
			(net "GND")
		)
		(pad "95" smd rect
			(at 0 85.000084 270)
			(size 1.8034 0.508)
			(layers "B.Cu" "B.Mask" "B.Paste")
			(net "M_C_DQ<36>")
		)
		(pad "96" smd rect
			(at 0 85.849968 270)
			(size 1.8034 0.508)
			(layers "B.Cu" "B.Mask" "B.Paste")
			(net "GND")
		)
		(pad "97" smd rect
			(at 0 86.700106 270)
			(size 1.8034 0.508)
			(layers "B.Cu" "B.Mask" "B.Paste")
			(net "M_C_DQ<32>")
		)
	)
)
